FILE_TYPE = CONNECTIVITY;
{Allegro Design Entry HDL 16.6-p007 (v16-6-112F) 10/10/2012}
"PAGE_NUMBER" = 172;
0"NC";
1"GND\g";
2"P12V\g";
3"GND\g";
4"P5V\g";
5"GND\g";
6"GND\g";
7"GND\g";
8"GND\g";
9"GND\g";
10"GND\g";
11"GND\g";
12"GND\g";
13"GND\g";
14"GND\g";
15"P5V_HDD_SATA"VOLTAGE"5";
16"SATA6G_S1_TX_C_DP";
17"SATA6G_S1_TX_C_DN";
18"SATA6G_S1_RX_C_DN";
19"P12V_HDD_SATA"VOLTAGE"12";
20"SATA6G_S1_RX_C_DP";
21"SATA6G_S1_RX_DP";
22"SATA6G_S1_RX_DN";
23"SATA6G_S1_TX_DN";
24"SATA6G_S1_TX_DP";
%"GND"
"1","(-650,50)","0","mstr_symbols","I35";
;
VOLTAGE"0"
CDS_LIB"mstr_symbols"
SIZE"1B"
ROOM"ST_SATA"
BODY_TYPE"PLUMBING"
HDL_POWER"GND";
"A\NAC"1;
%"CAP"
"1","(-650,250)","0","mstr_discrete","I36";
;
CDS_SEC"1"
LOCATION"C9B2"
TOLERANCE"10%"
PACK_TYPE"0805"
MATERIAL"X6S"
PART_NUMBER"C95333-007"
VOLTAGE"16V"
VALUE"10UF"
SEC_TYPE"0805"
SEC"1"
CDS_LIB"mstr_discrete"
CDS_LOCATION"C9B2"
ROOM"ST_SATA";
"A"
$PN"1"19;
"B"
$PN"2"1;
%"P12V"
"1","(1375,550)","0","mstr_symbols","I37";
;
SIZE"1B"
CDS_LIB"mstr_symbols"
VOLTAGE"12.0V"
BODY_TYPE"PLUMBING"
HDL_POWER"P12V";
"G\NAC"2;
%"CAP"
"1","(-1050,250)","0","mstr_discrete","I39";
;
CDS_SEC"1"
PACK_TYPE"0805"
PART_NUMBER"C95333-007"
MATERIAL"X6S"
TOLERANCE"10%"
VOLTAGE"16V"
VALUE"10UF"
LOCATION"C9B1"
CDS_LOCATION"C9B1"
CDS_LIB"mstr_discrete"
ROOM"ST_SATA"
SEC_TYPE"0805"
SEC"1";
"A"
$PN"1"15;
"B"
$PN"2"3;
%"GND"
"1","(-1050,50)","0","mstr_symbols","I40";
;
ROOM"ST_SATA"
SIZE"1B"
VOLTAGE"0"
CDS_LIB"mstr_symbols"
BODY_TYPE"PLUMBING"
HDL_POWER"GND";
"A\NAC"3;
%"P5V"
"1","(700,750)","0","mstr_symbols","I42";
;
VOLTAGE"+5.0V"
SIZE"1B"
CDS_LIB"mstr_symbols"
BODY_TYPE"PLUMBING"
HDL_POWER"P5V";
"G\NAC"4;
%"CAP_A"
"2","(1225,2100)","0","dev_discrete","I5";
;
PART_NUMBER"A36096-045"
VOLTAGE"25V"
MATERIAL"X7R"
PACK_TYPE"0402V"
VALUE"0.01UF"
LOCATION"C2L49"
TOLERANCE"10%"
CDS_LOCATION"C2L49"
CDS_SEC"1"
SEC_TYPE"0402V"
SEC"1"
ROOM"ST_SATA"
CDS_LIB"dev_discrete";
"A"
$PN"1"20;
"B"
$PN"2"21;
%"GND"
"1","(-1850,1500)","0","mstr_symbols","I57";
;
ROOM"ST_SATA"
SIZE"1B"
VOLTAGE"0"
CDS_LIB"mstr_symbols"
BODY_TYPE"PLUMBING"
HDL_POWER"GND";
"A\NAC"5;
%"GND"
"1","(-1850,2450)","0","mstr_symbols","I58";
;
ROOM"ST_SATA"
SIZE"1B"
VOLTAGE"0"
CDS_LIB"mstr_symbols"
BODY_TYPE"PLUMBING"
HDL_POWER"GND";
"A\NAC"6;
%"GND"
"1","(-1800,2200)","1","mstr_symbols","I59";
;
ROOM"ST_SATA"
SIZE"1B"
VOLTAGE"0"
CDS_LIB"mstr_symbols"
BODY_TYPE"PLUMBING"
HDL_POWER"GND";
"A\NAC"7;
%"CAP_A"
"2","(0,2300)","0","dev_discrete","I6";
;
VALUE"0.01UF"
MATERIAL"X7R"
PACK_TYPE"0402V"
LOCATION"C2L52"
TOLERANCE"10%"
VOLTAGE"25V"
PART_NUMBER"A36096-045"
ROOM"ST_SATA"
SEC"1"
SEC_TYPE"0402V"
CDS_SEC"1"
CDS_LOCATION"C2L52"
CDS_LIB"dev_discrete";
"A"
$PN"1"16;
"B"
$PN"2"24;
%"GND"
"1","(-1800,2050)","1","mstr_symbols","I60";
;
ROOM"ST_SATA"
SIZE"1B"
VOLTAGE"0"
CDS_LIB"mstr_symbols"
BODY_TYPE"PLUMBING"
HDL_POWER"GND";
"A\NAC"8;
%"GND"
"1","(-1850,1200)","0","mstr_symbols","I61";
;
CDS_LIB"mstr_symbols"
ROOM"ST_SATA"
SIZE"1B"
VOLTAGE"0"
BODY_TYPE"PLUMBING"
HDL_POWER"GND";
"A\NAC"9;
%"GND"
"1","(-1800,950)","1","mstr_symbols","I62";
;
CDS_LIB"mstr_symbols"
ROOM"ST_SATA"
SIZE"1B"
VOLTAGE"0"
BODY_TYPE"PLUMBING"
HDL_POWER"GND";
"A\NAC"10;
%"GND"
"1","(-1800,800)","1","mstr_symbols","I63";
;
ROOM"ST_SATA"
SIZE"1B"
VOLTAGE"0"
CDS_LIB"mstr_symbols"
BODY_TYPE"PLUMBING"
HDL_POWER"GND";
"A\NAC"11;
%"GND"
"1","(-1850,250)","0","mstr_symbols","I64";
;
VOLTAGE"0"
SIZE"1B"
ROOM"ST_SATA"
CDS_LIB"mstr_symbols"
BODY_TYPE"PLUMBING"
HDL_POWER"GND";
"A\NAC"12;
%"FUSE"
"1","(975,450)","4","mstr_discrete","I66";
;
MATERIAL"IC"
LOCATION"F9B1"
PART_NUMBER"C94311-016"
CDS_SEC"1"
CDS_LIB"mstr_discrete"
ROOM"ST_SATA"
PACK_TYPE"SM"
SEC_TYPE"SM"
SEC"1"
CDS_LOCATION"F9B1";
"A<SIZE-1..0>"
$PN"1"2;
"B<SIZE-1..0>"
$PN"2"19;
%"SKT-SATA7P-6P-165-GP-U1"
"1","(-2300,800)","0","w_hdl","I67";
;
CDS_SEC"1"
CDS_LOCATION"J2W1"
VALUE"SKT-SATA7P-6P-165-GP-U1"
LOCATION"J2W1"
BOM_SS"NOPOP"
CDS_LMAN_SYM_OUTLINE"-100,500,100,-500"
PART_NUMBER"022.10014.0121"
CDS_LIB"w_hdl"
SEC_TYPE"SOCKET-G6"
SEC"1"
PACK_TYPE"SOCKET-G6";
"H2"
$PN"H2"12;
"H1"
$PN"H1"9;
"NP2"
$PN"NP2"0;
"NP1"
$PN"NP1"0;
"P6"
$PN"P6"19;
"P5"
$PN"P5"19;
"P4"
$PN"P4"13;
"P3"
$PN"P3"13;
"P2"
$PN"P2"15;
"P1"
$PN"P1"15;
"S7"
$PN"S7"11;
"S6"
$PN"S6"20;
"S5"
$PN"S5"18;
"S4"
$PN"S4"10;
"S3"
$PN"S3"17;
"S2"
$PN"S2"16;
"S1"
$PN"S1"9;
%"SKT-SATA7P-6P-165-GP-U1"
"1","(-2300,2050)","0","w_hdl","I68";
;
CDS_SEC"1"
CDS_LOCATION"J2W2"
LOCATION"J2W2"
VALUE"SKT-SATA7P-6P-165-GP-U1"
BOM_DS"NOPOP"
PACK_TYPE"SOCKET-G6"
SEC"1"
SEC_TYPE"SOCKET-G6"
CDS_LIB"w_hdl"
PART_NUMBER"022.10014.0121"
CDS_LMAN_SYM_OUTLINE"-100,500,100,-500";
"H2"
$PN"H2"5;
"H1"
$PN"H1"6;
"NP2"
$PN"NP2"0;
"NP1"
$PN"NP1"0;
"P6"
$PN"P6"19;
"P5"
$PN"P5"19;
"P4"
$PN"P4"14;
"P3"
$PN"P3"14;
"P2"
$PN"P2"15;
"P1"
$PN"P1"15;
"S7"
$PN"S7"8;
"S6"
$PN"S6"20;
"S5"
$PN"S5"18;
"S4"
$PN"S4"7;
"S3"
$PN"S3"17;
"S2"
$PN"S2"16;
"S1"
$PN"S1"6;
%"GND"
"1","(-1800,550)","1","mstr_symbols","I69";
;
ROOM"ST_SATA"
SIZE"1B"
VOLTAGE"0"
CDS_LIB"mstr_symbols"
BODY_TYPE"PLUMBING"
HDL_POWER"GND";
"A\NAC"13;
%"CAP_A"
"2","(350,2150)","0","dev_discrete","I7";
;
VOLTAGE"25V"
MATERIAL"X7R"
PACK_TYPE"0402V"
TOLERANCE"10%"
PART_NUMBER"A36096-045"
LOCATION"C2L50"
VALUE"0.01UF"
CDS_LOCATION"C2L50"
CDS_SEC"1"
SEC_TYPE"0402V"
SEC"1"
ROOM"ST_SATA"
CDS_LIB"dev_discrete";
"A"
$PN"1"18;
"B"
$PN"2"22;
%"GND"
"1","(-1800,1800)","1","mstr_symbols","I70";
;
CDS_LIB"mstr_symbols"
VOLTAGE"0"
SIZE"1B"
ROOM"ST_SATA"
BODY_TYPE"PLUMBING"
HDL_POWER"GND";
"A\NAC"14;
%"FUSE-3A75V-GP"
"1","(175,650)","0","w_hdl","I71";
;
CDS_SEC"1"
CDS_LOCATION"F8B1"
LOCATION"F8B1"
VALUE"FUSE-3A75V-GP"
CDS_LIB"w_hdl"
PART_NUMBER"69.43001.511"
CDS_LMAN_SYM_OUTLINE"-75,50,75,-50"
PACK_TYPE"DISCRET-G5"
SEC"1"
SEC_TYPE"DISCRET-G5";
"2 \B"
$PN"2"4;
"1 \B"
$PN"1"15;
%"CAP_A"
"2","(750,2250)","0","dev_discrete","I8";
;
LOCATION"C2L51"
VALUE"0.01UF"
VOLTAGE"25V"
TOLERANCE"10%"
PACK_TYPE"0402V"
MATERIAL"X7R"
PART_NUMBER"A36096-045"
CDS_LOCATION"C2L51"
ROOM"ST_SATA"
SEC"1"
SEC_TYPE"0402V"
CDS_SEC"1"
CDS_LIB"dev_discrete";
"A"
$PN"1"17;
"B"
$PN"2"23;
END.
